# SCM (Grand Teton) — schematic netlist excerpt (pin names and nets, part order shuffled) for the footprints in the layout excerpt that follows; sources: Cadence DE-HDL packaged netlist, KiCad conversion of 12092022_DA0F0TMDCD0_F0T_Management_Board_D_brd_V3_OCP.brd

U25  LCMXO3LF2100C5BG256C  LCMXO3LF-2100C-5BG256C IC  pkg BGA256_0-8_14X14  page 34
  VCC_A1  = PVCCA_AUX_PLD
  NC1  = NC
  PT11C  = BSM_PRSNT_R1_N
  PT10A  = RST_PLTRST_R1_N
  PT11A  = RST_RSMRST_N
  \pt12d||tdi\  = JTAG_SCM_PLD_TDI
  \pt16c||tck\  = JTAG_SCM_PLD_TCK
  \pt17b||pclkc0_1\  = IRQ_BMC_PCH_NMI_R_N
  \pt18c||scl||pclkt0_0\  = SMB_BMC_MM16_R3_SCL
  PT19B  = NC
  PT21A  = RST_EXTRST_R_N
  PT22B  = FM_ADR_COMPLETE
  \pt24c||initn\  = PU_FPGA_NSTATUS
  PT22D  = SGPIO_CLK_PLD_0
  PT24B  = FM_THERMTRIP_DLY_LVC1_R_N
  VCC_A16  = PVCCA_AUX_PLD
  PL1C  = NC
  GND_B2  = GND
  PT9C  = IRQ_BMC_CPU_NMI_R
  PT11D  = RST_PCA9548_SENSOR_N
  PT9B  = FM_TPM_PRSNT_1_R_N
  PT11B  = FM_JTAG_BMC_MUX_SEL_R2
  PT13A  = IRQ_UV_DETECT_N
  \pt16d||tms\  = JTAG_SCM_PLD_TMS
  PT19A  = IRQ_PCH_SCI_WHEA_N
  \pt20d||programn\  = PU_PT20D
  PT22A  = IRQ_OC_DETECT_N
  PT23B  = SGPIO_PLD_LD_0
  PT22C  = IRQ_OC_DETECT_EN_N
  PT24A  = SGPIO_PLD_DI_0
  GND_B15  = GND
  PR1D  = FM_PECI_SEL_N
  PL2C  = NC
  PL1D  = NC
  GND_C3  = GND
  PT9A  = FM_TPM_PRSNT_0_R_N
  PT10B  = PWRGD_PSU_AC_PWROK_PLD
  \pt12c||tdo\  = JTAG_SCM_PLD_TDO
  PT13B  = RST_BMC_RSTBTN_OUT_N
  \pt17a||pclkt0_1\  = CLK_25M_OSC_FPGA
  \pt18d||sda||pclkc0_0\  = SMB_BMC_MM16_R3_SDA
  \pt20c||jtagenb\  = JTAG_SCM_PLD_R_JTAGEN
  PT21B  = PWRGD_CPUPWRGD_LVC1
  PT23A  = SGPIO_PLD_DO_0
  \pt24d||done\  = PU_FPGA_CONFIG_DONE
  GND_C14  = GND
  PR1C  = VOL_SEN_ALERT_R
  PR2C  = SMB_BMC_ALERT3_R1_N
  \pl1b||l_gpllc_fb\  = NC
  PL2D  = NC
  \pl1a||l_gpllt_fb\  = NC
  GND_D4  = GND
  VCCIO0_D5  = VCCIO0
  PT12A  = FM_BMC_DBP_PRESENT_N
  PT13D  = FM_ME_BT_DONE
  PT17C  = FM_PCH_BMC_THERMTRIP_N
  PT18B  = NC
  PT20A  = NC
  PT21D  = IRQ_CPU1_VRHOT_N
  VCCIO0_D12  = VCCIO0
  GND_D13  = GND
  PR1A  = H_CPU0_MEMTRIP_LVC1_N
  PR2D  = SMB_BMC_ALERT4_R1_N
  PR2A  = H_CPU1_MEMTRIP_LVC1_N
  \pl3a||pclkt5_0\  = NC
  \pl2a||l_gpllt_in\  = NC
  \pl2b||l_gpllc_in\  = NC
  VCCIO5  = VCCIO5
  GND_E5  = GND
  PT13C  = BMC_CPLD_GPIO_2_R2
  PT12B  = PWRGD_PCH_PWROK
  PT16B  = FM_BIOS_POST_CMPLT_BMC_N
  PT17D  = H_CPU1_PROCHOT_LVC1_R_N
  PT20B  = FM_CPU_MSMI_CATERR_LVT3_PLD_N
  PT19D  = TP_PLD_19D
  GND_E12  = GND
  VCCIO1_E13  = VCCIO1
  PR2B  = IRQ_SGPIO_R_N
  PR1B  = FM_SPD_REMOTE_EN_R
  PR3A  = RST_SGPIO_RESET_R_N
  PL4B  = NC
  \pl3b||pclkc5_0\  = NC
  PL4A  = NC
  PL3C  = NC
  PL5C  = NC
  GND_F6  = GND
  PT16A  = FM_PCIE_M2_SSD0_PRSNT_N
  PT18A  = RST_SRST_PLD_BMC_R2_N
  PT19C  = NC
  PT21C  = IRQ_CPU0_VRHOT_N
  GND_F11  = GND
  PR4C  = TP_PLD_L3
  PR3C  = SMB_BMC_ALERT9_R1_N
  PR4A  = BMC_CPLD_GPIO_8_R2
  PR3B  = BMC_CPLD_GPIO_7_R2
  PR4B  = NC
  PL6A  = NC
  PL5A  = NC
  PL5B  = NC
  PL4D  = NC
  PL4C  = NC
  PL3D  = NC
  VCC_G7  = PVCCA_AUX_PLD
  VCCIO0_G8  = VCCIO0
  VCCIO0_G9  = VCCIO0
  VCC_G10  = PVCCA_AUX_PLD
  PR5C  = FM_SLPS3_GF_R_N
  PR3D  = SMB_BMC_ALERT10_R1_N
  PR4D  = RST_BMC_SELF_HW_R2
  PR5B  = NC
  PR5A  = NC
  PR6A  = BMC_CPLD_GPIO_12_R2
  PL7B  = NC
  PL6B  = NC
  PL7A  = NC
  PL6C  = NC
  PL9C  = NC
  PL5D  = NC
  VCCIO4_H7  = VCCIO4
  GND_H8  = GND
  GND_H9  = GND
  VCCIO1_H10  = VCCIO1
  PR9C  = RST_MB_STBY_R_N
  PR5D  = RST_ROT_CPU_R_N
  PR6C  = FM_ESPI_PLD_R_EN
  \pr7a||pclkt1_0\  = NC
  PR6B  = BMC_CPLD_GPIO_13_R2
  \pr7b||pclkc1_0\  = NC
  \pl7c||pclkt4_0\  = NC
  PL9A  = NC
  \pl7d||pclkc4_0\  = NC
  PL9D  = NC
  PL10C  = NC
  PL6D  = NC
  VCCIO4_J7  = VCCIO4
  GND_J8  = GND
  GND_J9  = GND
  VCCIO1_J10  = VCCIO1
  PR10C  = NC
  PR6D  = FM_THROTTLE_R_N
  PR9D  = FM_ADR_TRIGGER_N
  PR7D  = H_CPU0_PROCHOT_LVC1_R_N
  PR9A  = RST_BMC_HW_R
  PR7C  = FM_PMBUS_ALERT_EN
  PL9B  = NC
  PL10B  = NC
  PL10A  = NC
  PL11C  = NC
  PL12C  = NC
  PL10D  = NC
  VCC_K7  = PVCCA_AUX_PLD
  VCCIO2_K8  = VCCIO2
  VCCIO2_K9  = VCCIO2
  VCC_K10  = PVCCA_AUX_PLD
  PR12C  = FM_PCHHOT_R_N
  PR11D  = FM_BIOS_DEBUG_EN_N
  PR11C  = FM_BMC_READY_PLD_N
  PR10A  = FM_PWR_R_BTN
  PR10B  = PWRGD_SYS_PWROK_PLD
  PR9B  = NC
  PL11A  = NC
  \pl12a||pclkt3_0\  = NC
  PL11B  = NC
  PL12D  = NC
  PL11D  = NC
  GND_L6  = GND
  PB8D  = NC_FM_PFR_NO_SERVICE_ACT_N
  PB11D  = FM_PFR_DSW_PWROK_N
  PB12D  = FM_BMC_CPU_FBRK_OUT_R_N
  PB18D  = FM_UARTSW_MSB_R_N
  GND_L11  = GND
  PR10D  = FM_BMC_EN_DET_R
  PR12D  = FM_BMC_ONCTL_R_N
  PR11B  = SMB_BMC_ALERT12_N
  PR12A  = NC
  PR11A  = USB_OC0_REAR_R_N
  \pl12b||pclkc3_0\  = NC
  PL14A  = NC
  PL13A  = NC
  VCCIO3  = VCCIO3
  GND_M5  = GND
  PB11C  = BMC_MONITER
  PB9C  = CLK_GEN2_BMC_RC_OE_N
  PB16C  = PWRGD_P1V8_AUX_R1
  PB18C  = FM_UARTSW_LSB_R_N
  PB21C  = PU_FPGA_NCONFIG
  PB19D  = NC
  GND_M12  = GND
  VCCIO1_M13  = VCCIO1
  PR13A  = PWR_LED_CPLD
  PR13B  = PWRGD_P5V_AUX_R1
  PR12B  = NC
  PL13B  = NC
  PL13C  = NC
  PL14B  = NC
  GND_N4  = GND
  VCCIO2_N5  = VCCIO2
  PB8C  = FM_BMC_DEBUG_SW_R2_N
  PB9D  = IRQ_SML0_ALERT_R_N
  PB12C  = CLK_BUF1_GPU_FPGA_OE_R_N
  PB16D  = PWRGD_P3V3_RGM_R1
  PB19C  = NC
  PB21D  = NC
  VCCIO2_N12  = VCCIO2
  GND_N13  = GND
  PR14B  = PWRGD_P2V5_AUX_R1
  PR13C  = AC_PWR_BTN_R2_N
  PR14A  = PWRGD_P3V3_AUX_R1
  PL13D  = NC
  PL14D  = NC
  GND_P3  = GND
  PB3A  = FM_P12V_HSC_ENABLE_R2
  PB5B  = TP_PLD_C13
  \pb8a||mclk||cclk\  = FM_HDD_LED_N
  PB9B  = GPU_WP_HW_CTRL_R_N
  PB12A  = GPU_FPGA_RST_N
  \pb16b||pclkc2_1\  = PWRGD_P1V0_AUX_R1
  PB19A  = NC
  PB21B  = NC
  PB24A  = NC
  \pb25b||si||sispi\  = NC
  GND_P14  = GND
  PR14C  = NC
  PR13D  = NC
  PL14C  = NC
  GND_R2  = GND
  PB3D  = PWRGD_DSW_PWROK_R2
  PB6D  = FM_BMC_SUSACK_R2_N
  \pb5a||csspin\  = FM_DEBUG_PORT_R2_PRSNT_N
  PB6B  = FM_BMC_CRASHLOG_TRIG_R2_N
  PB9A  = GPU_NVS_PWR_BRAKE_R_N
  \pb11b||pclkc2_0\  = NC_FM_PFR_UPDATE_N
  PB18A  = NC
  PB19B  = NC
  PB22A  = NC
  \pb25a||sn\  = PU_PB25A
  PB22C  = NC
  PB25D  = SMB_BMC_MM16_R4_SDA
  GND_R15  = GND
  PR14D  = SMB_BMC_ALERT16_R2_N
  VCC_T1  = PVCCA_AUX_PLD
  PB3C  = FM_SOL_UART_CH_SEL_R2
  PB6C  = RST_WDTRST_PLD_R2_N
  PB3B  = NC
  PB6A  = IRQ_PCH_TPM_SPI_R2_N
  \pb8b||so||spiso\  = FM_PCH_BEEP_LED
  \pb11a||pclkt2_0\  = RST_PFR_OVR_RTC_R
  PB12B  = FM_JTAG_TCK_MUX_BMC_SEL
  \pb16a||pclkt2_1\  = PWRGD_P1V2_AUX_R1
  PB18B  = NC
  PB21A  = NC
  PB22B  = NC
  PB24B  = NC
  PB22D  = NC
  PB25C  = SMB_BMC_MM16_R4_SCL
  VCC_T16  = PVCCA_AUX_PLD

(kicad_pcb
	(version 20260206)
	(generator "pcbnew")
	(generator_version "10.0")
	(general
		(thickness 1.6)
		(legacy_teardrops no)
	)
	(paper "A4")
	(title_block
		(title "12092022_DA0F0TMDCD0_F0T_Management_Board_D_brd_V3_OCP.brd")
		(comment 1 "Grand Teton / footprint 162 of 1440 (U25), pads 189-236 of 256")
	)
	(layers
		(0 "F.Cu" signal "TOP")
		(4 "In1.Cu" signal "GND")
		(6 "In2.Cu" signal "IN1")
		(8 "In3.Cu" signal "GND1")
		(10 "In4.Cu" signal "IN2")
		(12 "In5.Cu" signal "VCC")
		(14 "In6.Cu" signal "VCC1")
		(16 "In7.Cu" signal "IN3")
		(18 "In8.Cu" signal "GND2")
		(20 "In9.Cu" signal "IN4")
		(22 "In10.Cu" signal "GND3")
		(2 "B.Cu" signal "BOTTOM")
		(9 "F.Adhes" user "F.Adhesive")
		(11 "B.Adhes" user "B.Adhesive")
		(13 "F.Paste" user "Package Geometry/Pastemask Top")
		(15 "B.Paste" user "Package Geometry/Pastemask Bottom")
		(5 "F.SilkS" user "Ref Des/Silkscreen Top")
		(7 "B.SilkS" user "Ref Des/Silkscreen Bottom")
		(1 "F.Mask" user "Board Geometry/Soldermask Top")
		(3 "B.Mask" user "Board Geometry/Soldermask Bottom")
		(17 "Dwgs.User" user "User.Drawings")
		(19 "Cmts.User" user "User.Comments")
		(21 "Eco1.User" user "User.Eco1")
		(23 "Eco2.User" user "User.Eco2")
		(25 "Edge.Cuts" user "Board Geometry/Outline")
		(27 "Margin" user)
		(31 "F.CrtYd" user "Package Geometry/Place Bound Top")
		(29 "B.CrtYd" user "Package Geometry/Place Bound Bottom")
		(35 "F.Fab" user "Ref Des/Assembly Top")
		(33 "B.Fab" user "Ref Des/Assembly Bottom")
	)
	(footprint ""
		(layer "F.Cu")
		(at 21.459444 -93.587062 180)
		(property "Reference" "U25"
			(at -10.595356 -8.218932 0)
			(unlocked yes)
			(layer "F.SilkS")
			(effects
				(font
					(size 0.7874 0.5842)
					(thickness 0.1524)
				)
				(justify left)
			)
		)
		(property "Value" ""
			(at 0 0 180)
			(layer "F.Fab")
			(effects
				(font
					(size 1.27 1.27)
				)
			)
		)
		(duplicate_pad_numbers_are_jumpers no)
		(pad "M13" smd circle
			(at 3.599942 2.800096 180)
			(size 0.4064 0.4064)
			(layers "F.Cu" "F.Mask" "F.Paste")
			(net "VCCIO1")
		)
		(pad "M14" smd circle
			(at 4.400042 2.800096 180)
			(size 0.4064 0.4064)
			(layers "F.Cu" "F.Mask" "F.Paste")
			(net "PWR_LED_CPLD")
		)
		(pad "M15" smd circle
			(at 5.199888 2.800096 180)
			(size 0.4064 0.4064)
			(layers "F.Cu" "F.Mask" "F.Paste")
			(net "PWRGD_P5V_AUX_R1")
		)
		(pad "M16" smd circle
			(at 5.999988 2.800096 180)
			(size 0.4064 0.4064)
			(layers "F.Cu" "F.Mask" "F.Paste")
			(net "Net_79")
		)
		(pad "N1" smd circle
			(at -5.999988 3.599942 180)
			(size 0.4064 0.4064)
			(layers "F.Cu" "F.Mask" "F.Paste")
			(net "Net_273")
		)
		(pad "N2" smd circle
			(at -5.199888 3.599942 180)
			(size 0.4064 0.4064)
			(layers "F.Cu" "F.Mask" "F.Paste")
			(net "Net_274")
		)
		(pad "N3" smd circle
			(at -4.400042 3.599942 180)
			(size 0.4064 0.4064)
			(layers "F.Cu" "F.Mask" "F.Paste")
			(net "Net_277")
		)
		(pad "N4" smd circle
			(at -3.599942 3.599942 180)
			(size 0.4064 0.4064)
			(layers "F.Cu" "F.Mask" "F.Paste")
			(net "GND")
		)
		(pad "N5" smd circle
			(at -2.800096 3.599942 180)
			(size 0.4064 0.4064)
			(layers "F.Cu" "F.Mask" "F.Paste")
			(net "VCCIO2")
		)
		(pad "N6" smd circle
			(at -1.999996 3.599942 180)
			(size 0.4064 0.4064)
			(layers "F.Cu" "F.Mask" "F.Paste")
			(net "FM_BMC_DEBUG_SW_R2_N")
		)
		(pad "N7" smd circle
			(at -1.199896 3.599942 180)
			(size 0.4064 0.4064)
			(layers "F.Cu" "F.Mask" "F.Paste")
			(net "IRQ_SML0_ALERT_R_N")
		)
		(pad "N8" smd circle
			(at -0.40005 3.599942 180)
			(size 0.4064 0.4064)
			(layers "F.Cu" "F.Mask" "F.Paste")
			(net "CLK_BUF1_GPU_FPGA_OE_R_N")
		)
		(pad "N9" smd circle
			(at 0.40005 3.599942 180)
			(size 0.4064 0.4064)
			(layers "F.Cu" "F.Mask" "F.Paste")
			(net "PWRGD_P3V3_RGM_R1")
		)
		(pad "N10" smd circle
			(at 1.199896 3.599942 180)
			(size 0.4064 0.4064)
			(layers "F.Cu" "F.Mask" "F.Paste")
			(net "Net_252")
		)
		(pad "N11" smd circle
			(at 1.999996 3.599942 180)
			(size 0.4064 0.4064)
			(layers "F.Cu" "F.Mask" "F.Paste")
			(net "Net_256")
		)
		(pad "N12" smd circle
			(at 2.800096 3.599942 180)
			(size 0.4064 0.4064)
			(layers "F.Cu" "F.Mask" "F.Paste")
			(net "VCCIO2")
		)
		(pad "N13" smd circle
			(at 3.599942 3.599942 180)
			(size 0.4064 0.4064)
			(layers "F.Cu" "F.Mask" "F.Paste")
			(net "GND")
		)
		(pad "N14" smd circle
			(at 4.400042 3.599942 180)
			(size 0.4064 0.4064)
			(layers "F.Cu" "F.Mask" "F.Paste")
			(net "PWRGD_P2V5_AUX_R1")
		)
		(pad "N15" smd circle
			(at 5.199888 3.599942 180)
			(size 0.4064 0.4064)
			(layers "F.Cu" "F.Mask" "F.Paste")
			(net "AC_PWR_BTN_R2_N")
		)
		(pad "N16" smd circle
			(at 5.999988 3.599942 180)
			(size 0.4064 0.4064)
			(layers "F.Cu" "F.Mask" "F.Paste")
			(net "PWRGD_P3V3_AUX_R1")
		)
		(pad "P1" smd circle
			(at -5.999988 4.400042 180)
			(size 0.4064 0.4064)
			(layers "F.Cu" "F.Mask" "F.Paste")
			(net "Net_275")
		)
		(pad "P2" smd circle
			(at -5.199888 4.400042 180)
			(size 0.4064 0.4064)
			(layers "F.Cu" "F.Mask" "F.Paste")
			(net "Net_279")
		)
		(pad "P3" smd circle
			(at -4.400042 4.400042 180)
			(size 0.4064 0.4064)
			(layers "F.Cu" "F.Mask" "F.Paste")
			(net "GND")
		)
		(pad "P4" smd circle
			(at -3.599942 4.400042 180)
			(size 0.4064 0.4064)
			(layers "F.Cu" "F.Mask" "F.Paste")
			(net "FM_P12V_HSC_ENABLE_R2")
		)
		(pad "P5" smd circle
			(at -2.800096 4.400042 180)
			(size 0.4064 0.4064)
			(layers "F.Cu" "F.Mask" "F.Paste")
			(net "TP_PLD_C13")
		)
		(pad "P6" smd circle
			(at -1.999996 4.400042 180)
			(size 0.4064 0.4064)
			(layers "F.Cu" "F.Mask" "F.Paste")
			(net "FM_HDD_LED_N")
		)
		(pad "P7" smd circle
			(at -1.199896 4.400042 180)
			(size 0.4064 0.4064)
			(layers "F.Cu" "F.Mask" "F.Paste")
			(net "GPU_WP_HW_CTRL_R_N")
		)
		(pad "P8" smd circle
			(at -0.40005 4.400042 180)
			(size 0.4064 0.4064)
			(layers "F.Cu" "F.Mask" "F.Paste")
			(net "GPU_FPGA_RST_N")
		)
		(pad "P9" smd circle
			(at 0.40005 4.400042 180)
			(size 0.4064 0.4064)
			(layers "F.Cu" "F.Mask" "F.Paste")
			(net "PWRGD_P1V0_AUX_R1")
		)
		(pad "P10" smd circle
			(at 1.199896 4.400042 180)
			(size 0.4064 0.4064)
			(layers "F.Cu" "F.Mask" "F.Paste")
			(net "Net_250")
		)
		(pad "P11" smd circle
			(at 1.999996 4.400042 180)
			(size 0.4064 0.4064)
			(layers "F.Cu" "F.Mask" "F.Paste")
			(net "Net_255")
		)
		(pad "P12" smd circle
			(at 2.800096 4.400042 180)
			(size 0.4064 0.4064)
			(layers "F.Cu" "F.Mask" "F.Paste")
			(net "Net_261")
		)
		(pad "P13" smd circle
			(at 3.599942 4.400042 180)
			(size 0.4064 0.4064)
			(layers "F.Cu" "F.Mask" "F.Paste")
			(net "Net_263")
		)
		(pad "P14" smd circle
			(at 4.400042 4.400042 180)
			(size 0.4064 0.4064)
			(layers "F.Cu" "F.Mask" "F.Paste")
			(net "GND")
		)
		(pad "P15" smd circle
			(at 5.199888 4.400042 180)
			(size 0.4064 0.4064)
			(layers "F.Cu" "F.Mask" "F.Paste")
			(net "Net_74")
		)
		(pad "P16" smd circle
			(at 5.999988 4.400042 180)
			(size 0.4064 0.4064)
			(layers "F.Cu" "F.Mask" "F.Paste")
			(net "Net_73")
		)
		(pad "R1" smd circle
			(at -5.999988 5.199888 180)
			(size 0.4064 0.4064)
			(layers "F.Cu" "F.Mask" "F.Paste")
			(net "Net_278")
		)
		(pad "R2" smd circle
			(at -5.199888 5.199888 180)
			(size 0.4064 0.4064)
			(layers "F.Cu" "F.Mask" "F.Paste")
			(net "GND")
		)
		(pad "R3" smd circle
			(at -4.400042 5.199888 180)
			(size 0.4064 0.4064)
			(layers "F.Cu" "F.Mask" "F.Paste")
			(net "PWRGD_DSW_PWROK_R2")
		)
		(pad "R4" smd circle
			(at -3.599942 5.199888 180)
			(size 0.4064 0.4064)
			(layers "F.Cu" "F.Mask" "F.Paste")
			(net "FM_BMC_SUSACK_R2_N")
		)
		(pad "R5" smd circle
			(at -2.800096 5.199888 180)
			(size 0.4064 0.4064)
			(layers "F.Cu" "F.Mask" "F.Paste")
			(net "FM_DEBUG_PORT_R2_PRSNT_N")
		)
		(pad "R6" smd circle
			(at -1.999996 5.199888 180)
			(size 0.4064 0.4064)
			(layers "F.Cu" "F.Mask" "F.Paste")
			(net "FM_BMC_CRASHLOG_TRIG_R2_N")
		)
		(pad "R7" smd circle
			(at -1.199896 5.199888 180)
			(size 0.4064 0.4064)
			(layers "F.Cu" "F.Mask" "F.Paste")
			(net "GPU_NVS_PWR_BRAKE_R_N")
		)
		(pad "R8" smd circle
			(at -0.40005 5.199888 180)
			(size 0.4064 0.4064)
			(layers "F.Cu" "F.Mask" "F.Paste")
			(net "NC_FM_PFR_UPDATE_N")
		)
		(pad "R9" smd circle
			(at 0.40005 5.199888 180)
			(size 0.4064 0.4064)
			(layers "F.Cu" "F.Mask" "F.Paste")
			(net "Net_248")
		)
		(pad "R10" smd circle
			(at 1.199896 5.199888 180)
			(size 0.4064 0.4064)
			(layers "F.Cu" "F.Mask" "F.Paste")
			(net "Net_251")
		)
		(pad "R11" smd circle
			(at 1.999996 5.199888 180)
			(size 0.4064 0.4064)
			(layers "F.Cu" "F.Mask" "F.Paste")
			(net "Net_257")
		)
		(pad "R12" smd circle
			(at 2.800096 5.199888 180)
			(size 0.4064 0.4064)
			(layers "F.Cu" "F.Mask" "F.Paste")
			(net "PU_PB25A")
		)
	)
)
